FILE_TYPE=LIBRARY_PARTS;
primitive 'RCC_DFX1940';
  pin
    'GND':
      PIN_NUMBER='(1)';
      PINUSE='UNSPEC';
      NO_LOAD_CHECK='BOTH';
      NO_IO_CHECK='BOTH';
      ALLOW_CONNECT='TRUE';
    'IO1':
      PIN_NUMBER='(2)';
      PINUSE='UNSPEC';
      NO_LOAD_CHECK='BOTH';
      NO_IO_CHECK='BOTH';
      ALLOW_CONNECT='TRUE';
    'IO2':
      PIN_NUMBER='(3)';
      PINUSE='UNSPEC';
      NO_LOAD_CHECK='BOTH';
      NO_IO_CHECK='BOTH';
      ALLOW_CONNECT='TRUE';
  end_pin;
  body
    CLASS='IO';
    PART_NAME='RCC_DFX1940';
    PHYS_DES_PREFIX='TC';
  end_body;
end_primitive;
END.
